(kicad_pcb
	(version 20260206)
	(generator "pcbnew")
	(generator_version "10.0")
	(general
		(thickness 1.6)
		(legacy_teardrops no)
	)
	(paper "A4")
	(title_block
		(title "04192023_DAF0TMB3IC0_F0TG_MB_C_brd_V02_OCP.brd")
		(comment 1 "Grand Teton / footprints 4365-4370 of 8354")
	)
	(layers
		(0 "F.Cu" signal "TOP")
		(4 "In1.Cu" signal "GND")
		(6 "In2.Cu" signal "IN1")
		(8 "In3.Cu" signal "GND1")
		(10 "In4.Cu" signal "IN2")
		(12 "In5.Cu" signal "GND2")
		(14 "In6.Cu" signal "IN3")
		(16 "In7.Cu" signal "GND3")
		(18 "In8.Cu" signal "VCC")
		(20 "In9.Cu" signal "VCC1")
		(22 "In10.Cu" signal "GND4")
		(24 "In11.Cu" signal "IN4")
		(26 "In12.Cu" signal "GND5")
		(28 "In13.Cu" signal "IN5")
		(30 "In14.Cu" signal "GND6")
		(32 "In15.Cu" signal "IN6")
		(34 "In16.Cu" signal "GND7")
		(2 "B.Cu" signal "BOTTOM")
		(9 "F.Adhes" user "F.Adhesive")
		(11 "B.Adhes" user "B.Adhesive")
		(13 "F.Paste" user "Package Geometry/Pastemask Top")
		(15 "B.Paste" user "Package Geometry/Pastemask Bottom")
		(5 "F.SilkS" user "Ref Des/Silkscreen Top")
		(7 "B.SilkS" user "Ref Des/Silkscreen Bottom")
		(1 "F.Mask" user "Board Geometry/Soldermask Top")
		(3 "B.Mask" user "Board Geometry/Soldermask Bottom")
		(17 "Dwgs.User" user "User.Drawings")
		(19 "Cmts.User" user "User.Comments")
		(21 "Eco1.User" user "User.Eco1")
		(23 "Eco2.User" user "User.Eco2")
		(25 "Edge.Cuts" user "Board Geometry/Outline")
		(27 "Margin" user)
		(31 "F.CrtYd" user "Package Geometry/Place Bound Top")
		(29 "B.CrtYd" user "Package Geometry/Place Bound Bottom")
		(35 "F.Fab" user "Ref Des/Assembly Top")
		(33 "B.Fab" user "Ref Des/Assembly Bottom")
	)
	(footprint ""
		(layer "F.Cu")
		(at 157.037024 -26.68778 -90)
		(property "Reference" "R6018"
			(at 0 0 270)
			(layer "F.SilkS")
			(hide yes)
			(effects
				(font
					(size 1.27 1.27)
				)
			)
		)
		(property "Value" ""
			(at 0 0 270)
			(layer "F.Fab")
			(effects
				(font
					(size 1.27 1.27)
				)
			)
		)
		(duplicate_pad_numbers_are_jumpers no)
		(fp_line
			(start -0.7874 0.4064)
			(end -0.7874 -0.4064)
			(stroke
				(width 0.1524)
				(type default)
			)
			(layer "F.SilkS")
		)
		(fp_line
			(start 0.7874 0.4064)
			(end -0.7874 0.4064)
			(stroke
				(width 0.1524)
				(type default)
			)
			(layer "F.SilkS")
		)
		(fp_line
			(start -0.7874 -0.4064)
			(end 0.7874 -0.4064)
			(stroke
				(width 0.1524)
				(type default)
			)
			(layer "F.SilkS")
		)
		(fp_line
			(start 0.7874 -0.4064)
			(end 0.7874 0.4064)
			(stroke
				(width 0.1524)
				(type default)
			)
			(layer "F.SilkS")
		)
		(fp_line
			(start -0.67945 0.3048)
			(end -0.67945 -0.305054)
			(stroke
				(width 0.1)
				(type default)
			)
			(layer "F.Fab")
		)
		(fp_line
			(start -0.12065 0.3048)
			(end -0.67945 0.3048)
			(stroke
				(width 0.1)
				(type default)
			)
			(layer "F.Fab")
		)
		(fp_line
			(start 0.120396 0.3048)
			(end 0.120396 0.2794)
			(stroke
				(width 0.1)
				(type default)
			)
			(layer "F.Fab")
		)
		(fp_line
			(start 0.67945 0.3048)
			(end 0.120396 0.3048)
			(stroke
				(width 0.1)
				(type default)
			)
			(layer "F.Fab")
		)
		(fp_line
			(start -0.12065 0.2794)
			(end -0.12065 0.3048)
			(stroke
				(width 0.1)
				(type default)
			)
			(layer "F.Fab")
		)
		(fp_line
			(start 0.120396 0.2794)
			(end -0.12065 0.2794)
			(stroke
				(width 0.1)
				(type default)
			)
			(layer "F.Fab")
		)
		(fp_line
			(start -0.12065 -0.2794)
			(end 0.12065 -0.2794)
			(stroke
				(width 0.1)
				(type default)
			)
			(layer "F.Fab")
		)
		(fp_line
			(start 0.12065 -0.2794)
			(end 0.12065 -0.3048)
			(stroke
				(width 0.1)
				(type default)
			)
			(layer "F.Fab")
		)
		(fp_line
			(start 0.12065 -0.3048)
			(end 0.67945 -0.3048)
			(stroke
				(width 0.1)
				(type default)
			)
			(layer "F.Fab")
		)
		(fp_line
			(start 0.67945 -0.3048)
			(end 0.67945 0.3048)
			(stroke
				(width 0.1)
				(type default)
			)
			(layer "F.Fab")
		)
		(fp_line
			(start -0.67945 -0.305054)
			(end -0.12065 -0.305054)
			(stroke
				(width 0.1)
				(type default)
			)
			(layer "F.Fab")
		)
		(fp_line
			(start -0.12065 -0.305054)
			(end -0.12065 -0.2794)
			(stroke
				(width 0.1)
				(type default)
			)
			(layer "F.Fab")
		)
		(pad "1" smd circle
			(at -0.40005 0 270)
			(size 0 0)
			(layers "F.Cu" "F.Mask" "F.Paste")
			(net "P3V3_AUX")
		)
		(pad "2" smd circle
			(at 0.40005 0 270)
			(size 0 0)
			(layers "F.Cu" "F.Mask" "F.Paste")
			(net "SGPIO_SCM_DI_<0>")
		)
	)
	(footprint ""
		(layer "F.Cu")
		(at 398.893538 -393.04468)
		(property "Reference" "R1072"
			(at 0 0 0)
			(layer "F.SilkS")
			(hide yes)
			(effects
				(font
					(size 1.27 1.27)
				)
			)
		)
		(property "Value" ""
			(at 0 0 0)
			(layer "F.Fab")
			(effects
				(font
					(size 1.27 1.27)
				)
			)
		)
		(duplicate_pad_numbers_are_jumpers no)
		(fp_line
			(start -0.32512 -0.175006)
			(end 0.32512 -0.175006)
			(stroke
				(width 0.1)
				(type default)
			)
			(layer "F.Fab")
		)
		(fp_line
			(start -0.32512 0.175006)
			(end -0.32512 -0.175006)
			(stroke
				(width 0.1)
				(type default)
			)
			(layer "F.Fab")
		)
		(fp_line
			(start 0.32512 -0.175006)
			(end 0.32512 0.175006)
			(stroke
				(width 0.1)
				(type default)
			)
			(layer "F.Fab")
		)
		(fp_line
			(start 0.32512 0.175006)
			(end -0.32512 0.175006)
			(stroke
				(width 0.1)
				(type default)
			)
			(layer "F.Fab")
		)
		(pad "1" smd rect
			(at -0.2667 0)
			(size 0.3048 0.381)
			(layers "F.Cu" "F.Mask" "F.Paste")
			(net "GPIO3_RT_CPU0_P2")
		)
		(pad "2" smd rect
			(at 0.2667 0 180)
			(size 0.3048 0.381)
			(layers "F.Cu" "F.Mask" "F.Paste")
			(net "GND")
		)
	)
	(footprint ""
		(layer "F.Cu")
		(at 97.177352 -72.99198 180)
		(property "Reference" "R3631"
			(at 0 0 180)
			(layer "F.SilkS")
			(hide yes)
			(effects
				(font
					(size 1.27 1.27)
				)
			)
		)
		(property "Value" ""
			(at 0 0 180)
			(layer "F.Fab")
			(effects
				(font
					(size 1.27 1.27)
				)
			)
		)
		(duplicate_pad_numbers_are_jumpers no)
		(fp_line
			(start 0.7874 0.4064)
			(end -0.7874 0.4064)
			(stroke
				(width 0.1524)
				(type default)
			)
			(layer "F.SilkS")
		)
		(fp_line
			(start 0.7874 -0.4064)
			(end 0.7874 0.4064)
			(stroke
				(width 0.1524)
				(type default)
			)
			(layer "F.SilkS")
		)
		(fp_line
			(start -0.7874 0.4064)
			(end -0.7874 -0.4064)
			(stroke
				(width 0.1524)
				(type default)
			)
			(layer "F.SilkS")
		)
		(fp_line
			(start -0.7874 -0.4064)
			(end 0.7874 -0.4064)
			(stroke
				(width 0.1524)
				(type default)
			)
			(layer "F.SilkS")
		)
		(fp_line
			(start 0.67945 0.3048)
			(end 0.120396 0.3048)
			(stroke
				(width 0.1)
				(type default)
			)
			(layer "F.Fab")
		)
		(fp_line
			(start 0.67945 -0.3048)
			(end 0.67945 0.3048)
			(stroke
				(width 0.1)
				(type default)
			)
			(layer "F.Fab")
		)
		(fp_line
			(start 0.12065 -0.2794)
			(end 0.12065 -0.3048)
			(stroke
				(width 0.1)
				(type default)
			)
			(layer "F.Fab")
		)
		(fp_line
			(start 0.12065 -0.3048)
			(end 0.67945 -0.3048)
			(stroke
				(width 0.1)
				(type default)
			)
			(layer "F.Fab")
		)
		(fp_line
			(start 0.120396 0.3048)
			(end 0.120396 0.2794)
			(stroke
				(width 0.1)
				(type default)
			)
			(layer "F.Fab")
		)
		(fp_line
			(start 0.120396 0.2794)
			(end -0.12065 0.2794)
			(stroke
				(width 0.1)
				(type default)
			)
			(layer "F.Fab")
		)
		(fp_line
			(start -0.12065 0.3048)
			(end -0.67945 0.3048)
			(stroke
				(width 0.1)
				(type default)
			)
			(layer "F.Fab")
		)
		(fp_line
			(start -0.12065 0.2794)
			(end -0.12065 0.3048)
			(stroke
				(width 0.1)
				(type default)
			)
			(layer "F.Fab")
		)
		(fp_line
			(start -0.12065 -0.2794)
			(end 0.12065 -0.2794)
			(stroke
				(width 0.1)
				(type default)
			)
			(layer "F.Fab")
		)
		(fp_line
			(start -0.12065 -0.305054)
			(end -0.12065 -0.2794)
			(stroke
				(width 0.1)
				(type default)
			)
			(layer "F.Fab")
		)
		(fp_line
			(start -0.67945 0.3048)
			(end -0.67945 -0.305054)
			(stroke
				(width 0.1)
				(type default)
			)
			(layer "F.Fab")
		)
		(fp_line
			(start -0.67945 -0.305054)
			(end -0.12065 -0.305054)
			(stroke
				(width 0.1)
				(type default)
			)
			(layer "F.Fab")
		)
		(pad "1" smd circle
			(at -0.40005 0 180)
			(size 0 0)
			(layers "F.Cu" "F.Mask" "F.Paste")
			(net "P3V3_OCP_V3_2_EN_R")
		)
		(pad "2" smd circle
			(at 0.40005 0 180)
			(size 0 0)
			(layers "F.Cu" "F.Mask" "F.Paste")
			(net "P3V3_OCP_EN_2")
		)
	)
	(footprint ""
		(layer "F.Cu")
		(at 179.236878 -353.960684 90)
		(property "Reference" "PC505"
			(at 0 0 90)
			(layer "F.SilkS")
			(hide yes)
			(effects
				(font
					(size 1.27 1.27)
				)
			)
		)
		(property "Value" ""
			(at 0 0 90)
			(layer "F.Fab")
			(effects
				(font
					(size 1.27 1.27)
				)
			)
		)
		(duplicate_pad_numbers_are_jumpers no)
		(fp_line
			(start 0.7874 -0.4064)
			(end 0.7874 0.4064)
			(stroke
				(width 0.1524)
				(type default)
			)
			(layer "F.SilkS")
		)
		(fp_line
			(start -0.7874 -0.4064)
			(end 0.7874 -0.4064)
			(stroke
				(width 0.1524)
				(type default)
			)
			(layer "F.SilkS")
		)
		(fp_line
			(start 0.7874 0.4064)
			(end 0.420116 0.4064)
			(stroke
				(width 0.1524)
				(type default)
			)
			(layer "F.SilkS")
		)
		(fp_line
			(start -0.265684 0.4064)
			(end -0.7874 0.4064)
			(stroke
				(width 0.1524)
				(type default)
			)
			(layer "F.SilkS")
		)
		(fp_line
			(start -0.7874 0.4064)
			(end -0.7874 -0.4064)
			(stroke
				(width 0.1524)
				(type default)
			)
			(layer "F.SilkS")
		)
		(fp_line
			(start -0.12065 -0.305054)
			(end -0.12065 -0.2794)
			(stroke
				(width 0.1)
				(type default)
			)
			(layer "F.Fab")
		)
		(fp_line
			(start -0.67945 -0.305054)
			(end -0.12065 -0.305054)
			(stroke
				(width 0.1)
				(type default)
			)
			(layer "F.Fab")
		)
		(fp_line
			(start 0.67945 -0.3048)
			(end 0.67945 0.3048)
			(stroke
				(width 0.1)
				(type default)
			)
			(layer "F.Fab")
		)
		(fp_line
			(start 0.12065 -0.3048)
			(end 0.67945 -0.3048)
			(stroke
				(width 0.1)
				(type default)
			)
			(layer "F.Fab")
		)
		(fp_line
			(start 0.12065 -0.2794)
			(end 0.12065 -0.3048)
			(stroke
				(width 0.1)
				(type default)
			)
			(layer "F.Fab")
		)
		(fp_line
			(start -0.12065 -0.2794)
			(end 0.12065 -0.2794)
			(stroke
				(width 0.1)
				(type default)
			)
			(layer "F.Fab")
		)
		(fp_line
			(start 0.120396 0.2794)
			(end -0.12065 0.2794)
			(stroke
				(width 0.1)
				(type default)
			)
			(layer "F.Fab")
		)
		(fp_line
			(start -0.12065 0.2794)
			(end -0.12065 0.3048)
			(stroke
				(width 0.1)
				(type default)
			)
			(layer "F.Fab")
		)
		(fp_line
			(start 0.67945 0.3048)
			(end 0.120396 0.3048)
			(stroke
				(width 0.1)
				(type default)
			)
			(layer "F.Fab")
		)
		(fp_line
			(start 0.120396 0.3048)
			(end 0.120396 0.2794)
			(stroke
				(width 0.1)
				(type default)
			)
			(layer "F.Fab")
		)
		(fp_line
			(start -0.12065 0.3048)
			(end -0.67945 0.3048)
			(stroke
				(width 0.1)
				(type default)
			)
			(layer "F.Fab")
		)
		(fp_line
			(start -0.67945 0.3048)
			(end -0.67945 -0.305054)
			(stroke
				(width 0.1)
				(type default)
			)
			(layer "F.Fab")
		)
		(pad "1" smd circle
			(at -0.40005 0 90)
			(size 0 0)
			(layers "F.Cu" "F.Mask" "F.Paste")
			(net "PVDD11_S3_P1_VCC1")
		)
		(pad "2" smd circle
			(at 0.40005 0 90)
			(size 0 0)
			(layers "F.Cu" "F.Mask" "F.Paste")
			(net "GND")
		)
	)
	(footprint ""
		(layer "F.Cu")
		(at 21.075396 -339.223604 90)
		(property "Reference" "PL46"
			(at 0 -3.978148 90)
			(unlocked yes)
			(layer "F.SilkS")
			(effects
				(font
					(size 0.7874 0.5842)
					(thickness 0.1524)
				)
				(justify left)
			)
		)
		(property "Value" ""
			(at 0 0 90)
			(layer "F.Fab")
			(effects
				(font
					(size 1.27 1.27)
				)
			)
		)
		(duplicate_pad_numbers_are_jumpers no)
		(fp_line
			(start 3.24993 -3.24993)
			(end 3.24993 -2.2352)
			(stroke
				(width 0.1524)
				(type default)
			)
			(layer "F.SilkS")
		)
		(fp_line
			(start -3.24993 -3.24993)
			(end 3.24993 -3.24993)
			(stroke
				(width 0.1524)
				(type default)
			)
			(layer "F.SilkS")
		)
		(fp_line
			(start -3.24993 -2.2352)
			(end -3.24993 -3.24993)
			(stroke
				(width 0.1524)
				(type default)
			)
			(layer "F.SilkS")
		)
		(fp_line
			(start 3.24993 2.2352)
			(end 3.24993 3.24993)
			(stroke
				(width 0.1524)
				(type default)
			)
			(layer "F.SilkS")
		)
		(fp_line
			(start 3.24993 3.24993)
			(end -3.24993 3.24993)
			(stroke
				(width 0.1524)
				(type default)
			)
			(layer "F.SilkS")
		)
		(fp_line
			(start -3.24993 3.24993)
			(end -3.24993 2.2352)
			(stroke
				(width 0.1524)
				(type default)
			)
			(layer "F.SilkS")
		)
		(fp_line
			(start 3.24993 -3.24993)
			(end 3.24993 3.24993)
			(stroke
				(width 0.1)
				(type default)
			)
			(layer "F.Fab")
		)
		(fp_line
			(start -3.24993 -3.24993)
			(end 3.24993 -3.24993)
			(stroke
				(width 0.1)
				(type default)
			)
			(layer "F.Fab")
		)
		(fp_line
			(start 3.24993 3.24993)
			(end -3.24993 3.24993)
			(stroke
				(width 0.1)
				(type default)
			)
			(layer "F.Fab")
		)
		(fp_line
			(start -3.24993 3.24993)
			(end -3.24993 -3.24993)
			(stroke
				(width 0.1)
				(type default)
			)
			(layer "F.Fab")
		)
		(pad "1" smd rect
			(at -2.29997 0 90)
			(size 2.0066 4.2164)
			(layers "F.Cu" "F.Mask" "F.Paste")
			(net "IND_PVDDIO_P1_CPL0")
		)
		(pad "2" smd rect
			(at 2.29997 0 90)
			(size 2.0066 4.2164)
			(layers "F.Cu" "F.Mask" "F.Paste")
			(net "GND")
		)
	)
	(footprint ""
		(layer "F.Cu")
		(at 166.3192 -434.869336)
		(property "Reference" "R2724"
			(at 0 0 0)
			(layer "F.SilkS")
			(hide yes)
			(effects
				(font
					(size 1.27 1.27)
				)
			)
		)
		(property "Value" ""
			(at 0 0 0)
			(layer "F.Fab")
			(effects
				(font
					(size 1.27 1.27)
				)
			)
		)
		(duplicate_pad_numbers_are_jumpers no)
		(fp_line
			(start -0.7874 -0.4064)
			(end 0.7874 -0.4064)
			(stroke
				(width 0.1524)
				(type default)
			)
			(layer "F.SilkS")
		)
		(fp_line
			(start -0.7874 0.4064)
			(end -0.7874 -0.4064)
			(stroke
				(width 0.1524)
				(type default)
			)
			(layer "F.SilkS")
		)
		(fp_line
			(start 0.7874 -0.4064)
			(end 0.7874 0.4064)
			(stroke
				(width 0.1524)
				(type default)
			)
			(layer "F.SilkS")
		)
		(fp_line
			(start 0.7874 0.4064)
			(end -0.7874 0.4064)
			(stroke
				(width 0.1524)
				(type default)
			)
			(layer "F.SilkS")
		)
		(fp_line
			(start -0.67945 -0.305054)
			(end -0.12065 -0.305054)
			(stroke
				(width 0.1)
				(type default)
			)
			(layer "F.Fab")
		)
		(fp_line
			(start -0.67945 0.3048)
			(end -0.67945 -0.305054)
			(stroke
				(width 0.1)
				(type default)
			)
			(layer "F.Fab")
		)
		(fp_line
			(start -0.12065 -0.305054)
			(end -0.12065 -0.2794)
			(stroke
				(width 0.1)
				(type default)
			)
			(layer "F.Fab")
		)
		(fp_line
			(start -0.12065 -0.2794)
			(end 0.12065 -0.2794)
			(stroke
				(width 0.1)
				(type default)
			)
			(layer "F.Fab")
		)
		(fp_line
			(start -0.12065 0.2794)
			(end -0.12065 0.3048)
			(stroke
				(width 0.1)
				(type default)
			)
			(layer "F.Fab")
		)
		(fp_line
			(start -0.12065 0.3048)
			(end -0.67945 0.3048)
			(stroke
				(width 0.1)
				(type default)
			)
			(layer "F.Fab")
		)
		(fp_line
			(start 0.120396 0.2794)
			(end -0.12065 0.2794)
			(stroke
				(width 0.1)
				(type default)
			)
			(layer "F.Fab")
		)
		(fp_line
			(start 0.120396 0.3048)
			(end 0.120396 0.2794)
			(stroke
				(width 0.1)
				(type default)
			)
			(layer "F.Fab")
		)
		(fp_line
			(start 0.12065 -0.3048)
			(end 0.67945 -0.3048)
			(stroke
				(width 0.1)
				(type default)
			)
			(layer "F.Fab")
		)
		(fp_line
			(start 0.12065 -0.2794)
			(end 0.12065 -0.3048)
			(stroke
				(width 0.1)
				(type default)
			)
			(layer "F.Fab")
		)
		(fp_line
			(start 0.67945 -0.3048)
			(end 0.67945 0.3048)
			(stroke
				(width 0.1)
				(type default)
			)
			(layer "F.Fab")
		)
		(fp_line
			(start 0.67945 0.3048)
			(end 0.120396 0.3048)
			(stroke
				(width 0.1)
				(type default)
			)
			(layer "F.Fab")
		)
		(pad "1" smd circle
			(at -0.40005 0)
			(size 0 0)
			(layers "F.Cu" "F.Mask" "F.Paste")
			(net "SMB_BMC_SWB_R_SDA")
		)
		(pad "2" smd circle
			(at 0.40005 0)
			(size 0 0)
			(layers "F.Cu" "F.Mask" "F.Paste")
			(net "SMB_BMC_SWB_BUF_R_SDA")
		)
	)
)
